(kicad_pcb
	(version 20241229)
	(generator "pcbnew")
	(generator_version "9.0")
	(general
		(thickness 1.294)
		(legacy_teardrops no)
	)
	(paper "A3")
	(title_block
		(title "Kintex 410T devboard")
		(date "2024-04-03")
		(rev "1.1.2")
		(comment 9 "footprints 881-885 of 975")
	)
	(layers
		(0 "F.Cu" mixed)
		(4 "In1.Cu" power)
		(6 "In2.Cu" power)
		(8 "In3.Cu" mixed)
		(10 "In4.Cu" power)
		(12 "In5.Cu" mixed)
		(14 "In6.Cu" power)
		(16 "In7.Cu" mixed)
		(18 "In8.Cu" power)
		(2 "B.Cu" mixed)
		(9 "F.Adhes" user "F.Adhesive")
		(11 "B.Adhes" user "B.Adhesive")
		(13 "F.Paste" user)
		(15 "B.Paste" user)
		(5 "F.SilkS" user "F.Silkscreen")
		(7 "B.SilkS" user "B.Silkscreen")
		(1 "F.Mask" user)
		(3 "B.Mask" user)
		(17 "Dwgs.User" user "User.Drawings")
		(19 "Cmts.User" user "User.Comments")
		(21 "Eco1.User" user "User.Eco1")
		(23 "Eco2.User" user "User.Eco2")
		(25 "Edge.Cuts" user)
		(27 "Margin" user)
		(31 "F.CrtYd" user "F.Courtyard")
		(29 "B.CrtYd" user "B.Courtyard")
		(35 "F.Fab" user)
		(33 "B.Fab" user)
	)
	(footprint "antmicro-footprints:R_Array_4x0201_Panasonic_EXB18V"
		(layer "B.Cu")
		(at 255.2 73.4 180)
		(property "Reference" "R132"
			(at 1.475 0.75 0)
			(layer "B.SilkS")
			(effects
				(font
					(size 0.7 0.7)
					(thickness 0.15)
				)
				(justify right bottom mirror)
			)
		)
		(property "Value" "4x10k_0201_array"
			(at -1.1 -1.8 0)
			(layer "B.Fab")
			(effects
				(font
					(size 0.7 0.7)
					(thickness 0.15)
				)
				(justify left bottom mirror)
			)
		)
		(property "Description" "Fixed Network Resistor, 10 kohm, Isolated, 4 Resistors, 0502 [1406 Metric], Flat, ± 5%"
			(at 0 0 180)
			(layer "F.Fab")
			(hide yes)
			(effects
				(font
					(size 1.27 1.27)
					(thickness 0.15)
				)
			)
		)
		(property "Author" "Antmicro"
			(at 510.4 146.8 0)
			(layer "B.Fab")
			(hide yes)
			(effects
				(font
					(size 1 1)
					(thickness 0.15)
				)
				(justify mirror)
			)
		)
		(property "License" "Apache-2.0"
			(at 510.4 146.8 0)
			(layer "B.Fab")
			(hide yes)
			(effects
				(font
					(size 1 1)
					(thickness 0.15)
				)
				(justify mirror)
			)
		)
		(property "MPN" "EXB-18V103JX"
			(at 510.4 146.8 0)
			(layer "B.Fab")
			(hide yes)
			(effects
				(font
					(size 1 1)
					(thickness 0.15)
				)
				(justify mirror)
			)
		)
		(property "Manufacturer" "Panasonic"
			(at 510.4 146.8 0)
			(layer "B.Fab")
			(hide yes)
			(effects
				(font
					(size 1 1)
					(thickness 0.15)
				)
				(justify mirror)
			)
		)
		(property "Val" "4x10k_0201"
			(at 510.4 146.8 0)
			(layer "B.Fab")
			(hide yes)
			(effects
				(font
					(size 1 1)
					(thickness 0.15)
				)
				(justify mirror)
			)
		)
		(sheetname "User GPIO + LED + button + DIP switch")
		(sheetfile "user-gpio.kicad_sch")
		(attr smd)
		(fp_line
			(start 0.8 0.45)
			(end 0.8 -0.45)
			(stroke
				(width 0.12)
				(type solid)
			)
			(layer "B.SilkS")
		)
		(fp_line
			(start -0.8 0.45)
			(end -0.8 -0.45)
			(stroke
				(width 0.12)
				(type solid)
			)
			(layer "B.SilkS")
		)
		(fp_rect
			(start -0.898 0.66)
			(end 0.898 -0.65)
			(stroke
				(width 0.05)
				(type solid)
			)
			(fill no)
			(layer "B.CrtYd")
		)
		(pad "1" smd roundrect
			(at -0.6 -0.298 180)
			(size 0.2 0.4)
			(layers "B.Cu" "B.Mask" "B.Paste")
			(roundrect_rratio 0.25)
			(net 1308 "/USER_IO.DIP_SW3")
			(pinfunction "R1.1")
			(pintype "passive")
		)
		(pad "2" smd roundrect
			(at -0.202 -0.298 180)
			(size 0.2 0.4)
			(layers "B.Cu" "B.Mask" "B.Paste")
			(roundrect_rratio 0.25)
			(net 1309 "/USER_IO.DIP_SW2")
			(pinfunction "R2.1")
			(pintype "passive")
		)
		(pad "3" smd roundrect
			(at 0.2 -0.298 180)
			(size 0.2 0.4)
			(layers "B.Cu" "B.Mask" "B.Paste")
			(roundrect_rratio 0.25)
			(net 1310 "/USER_IO.DIP_SW1")
			(pinfunction "R3.1")
			(pintype "passive")
		)
		(pad "4" smd roundrect
			(at 0.598 -0.298 180)
			(size 0.2 0.4)
			(layers "B.Cu" "B.Mask" "B.Paste")
			(roundrect_rratio 0.25)
			(net 1311 "/USER_IO.DIP_SW0")
			(pinfunction "R4.1")
			(pintype "passive")
		)
		(pad "5" smd roundrect
			(at 0.598 0.3 180)
			(size 0.2 0.4)
			(layers "B.Cu" "B.Mask" "B.Paste")
			(roundrect_rratio 0.25)
			(net 26 "+1V8")
			(pinfunction "R4.2")
			(pintype "passive")
		)
		(pad "6" smd roundrect
			(at 0.2 0.3 180)
			(size 0.2 0.4)
			(layers "B.Cu" "B.Mask" "B.Paste")
			(roundrect_rratio 0.25)
			(net 26 "+1V8")
			(pinfunction "R3.2")
			(pintype "passive")
		)
		(pad "7" smd roundrect
			(at -0.202 0.3 180)
			(size 0.2 0.4)
			(layers "B.Cu" "B.Mask" "B.Paste")
			(roundrect_rratio 0.25)
			(net 26 "+1V8")
			(pinfunction "R2.2")
			(pintype "passive")
		)
		(pad "8" smd roundrect
			(at -0.6 0.3 180)
			(size 0.2 0.4)
			(layers "B.Cu" "B.Mask" "B.Paste")
			(roundrect_rratio 0.25)
			(net 26 "+1V8")
			(pinfunction "R1.2")
			(pintype "passive")
		)
	)
	(footprint "antmicro-footprints:C_0402_1005Metric"
		(layer "B.Cu")
		(at 194.775 127.825)
		(descr "Capacitor SMD 0402")
		(tags "capacitor SMD 0402")
		(property "Reference" "C134"
			(at 24.475 -28.775 180)
			(layer "B.SilkS")
			(effects
				(font
					(size 0.7 0.7)
					(thickness 0.15)
				)
				(justify left bottom mirror)
			)
		)
		(property "Value" "C_100n_0402"
			(at 0 -1.169 180)
			(layer "B.Fab")
			(effects
				(font
					(size 0.7 0.7)
					(thickness 0.15)
				)
				(justify left bottom mirror)
			)
		)
		(property "Description" "SMD Multilayer Ceramic Capacitor, 0.1 µF, 50 V, 0402 [1005 Metric], ± 10%, X5R, GRM Series"
			(at 0 0 0)
			(layer "F.Fab")
			(hide yes)
			(effects
				(font
					(size 1.27 1.27)
					(thickness 0.15)
				)
			)
		)
		(property "Author" "Antmicro"
			(at 0 0 0)
			(layer "B.Fab")
			(hide yes)
			(effects
				(font
					(size 1 1)
					(thickness 0.15)
				)
				(justify mirror)
			)
		)
		(property "Dielectric" "X5R"
			(at 0 0 0)
			(layer "B.Fab")
			(hide yes)
			(effects
				(font
					(size 1 1)
					(thickness 0.15)
				)
				(justify mirror)
			)
		)
		(property "License" "Apache-2.0"
			(at 0 0 0)
			(layer "B.Fab")
			(hide yes)
			(effects
				(font
					(size 1 1)
					(thickness 0.15)
				)
				(justify mirror)
			)
		)
		(property "MPN" "GRM155R61H104KE14D"
			(at 0 0 0)
			(layer "B.Fab")
			(hide yes)
			(effects
				(font
					(size 1 1)
					(thickness 0.15)
				)
				(justify mirror)
			)
		)
		(property "Manufacturer" "Murata"
			(at 0 0 0)
			(layer "B.Fab")
			(hide yes)
			(effects
				(font
					(size 1 1)
					(thickness 0.15)
				)
				(justify mirror)
			)
		)
		(property "Val" "100n"
			(at 0 0 0)
			(layer "B.Fab")
			(hide yes)
			(effects
				(font
					(size 1 1)
					(thickness 0.15)
				)
				(justify mirror)
			)
		)
		(property "Voltage" "50V"
			(at 0 0 0)
			(layer "B.Fab")
			(hide yes)
			(effects
				(font
					(size 1 1)
					(thickness 0.15)
				)
				(justify mirror)
			)
		)
		(sheetname "FPGA supply")
		(sheetfile "fpga-supply.kicad_sch")
		(attr smd)
		(fp_rect
			(start -0.925 0.47)
			(end 0.925 -0.47)
			(stroke
				(width 0.05)
				(type default)
			)
			(fill no)
			(layer "B.CrtYd")
		)
		(fp_line
			(start -0.494 -0.248)
			(end -0.494 0.25)
			(stroke
				(width 0.15)
				(type solid)
			)
			(layer "B.Fab")
		)
		(fp_line
			(start -0.494 0.25)
			(end 0.504 0.25)
			(stroke
				(width 0.15)
				(type solid)
			)
			(layer "B.Fab")
		)
		(fp_line
			(start 0.504 -0.248)
			(end -0.494 -0.248)
			(stroke
				(width 0.15)
				(type solid)
			)
			(layer "B.Fab")
		)
		(fp_line
			(start 0.504 0.25)
			(end 0.504 -0.248)
			(stroke
				(width 0.15)
				(type solid)
			)
			(layer "B.Fab")
		)
		(pad "1" smd roundrect
			(at -0.48 0)
			(size 0.59 0.64)
			(layers "B.Cu" "B.Mask" "B.Paste")
			(roundrect_rratio 0.25)
			(net 1 "GND")
			(pintype "passive")
		)
		(pad "2" smd roundrect
			(at 0.48 0)
			(size 0.59 0.64)
			(layers "B.Cu" "B.Mask" "B.Paste")
			(roundrect_rratio 0.25)
			(net 650 "+1V0")
			(pintype "passive")
		)
	)
	(footprint "antmicro-footprints:R_0402_1005Metric_EIA"
		(layer "B.Cu")
		(at 191 137.5)
		(descr "Resistor SMD 0402 (1005 Metric), square (rectangular) end terminal, IPC_7351 nominal, (Body size source: IPC-SM-782 page 76, https://www.pcb-3d.com/wordpress/wp-content/uploads/ipc-sm-782a_amendment_1_and_2.pdf)")
		(tags "resistor 0402")
		(property "Reference" "R340"
			(at 2.8 2.275 180)
			(layer "B.SilkS")
			(effects
				(font
					(size 0.7 0.7)
					(thickness 0.15)
				)
				(justify left bottom mirror)
			)
		)
		(property "Value" "R_80R6_0402_EIA"
			(at 0 -1.169 180)
			(layer "B.Fab")
			(effects
				(font
					(size 0.7 0.7)
					(thickness 0.15)
				)
				(justify left bottom mirror)
			)
		)
		(property "Description" "SMD Chip Resistor, 80.6 ohm, ± 1%, 62.5 mW, 0402 [1005 Metric], Thick Film, General Purpose"
			(at 0 0 0)
			(layer "F.Fab")
			(hide yes)
			(effects
				(font
					(size 1.27 1.27)
					(thickness 0.15)
				)
			)
		)
		(property "Author" "Antmicro"
			(at 0 0 0)
			(layer "B.Fab")
			(hide yes)
			(effects
				(font
					(size 1 1)
					(thickness 0.15)
				)
				(justify mirror)
			)
		)
		(property "License" "Apache-2.0"
			(at 0 0 0)
			(layer "B.Fab")
			(hide yes)
			(effects
				(font
					(size 1 1)
					(thickness 0.15)
				)
				(justify mirror)
			)
		)
		(property "MPN" "MC00625W0402180R6"
			(at 0 0 0)
			(layer "B.Fab")
			(hide yes)
			(effects
				(font
					(size 1 1)
					(thickness 0.15)
				)
				(justify mirror)
			)
		)
		(property "Manufacturer" "Multicomp Pro"
			(at 0 0 0)
			(layer "B.Fab")
			(hide yes)
			(effects
				(font
					(size 1 1)
					(thickness 0.15)
				)
				(justify mirror)
			)
		)
		(property "Tolerance" "1%"
			(at 0 0 0)
			(layer "B.Fab")
			(hide yes)
			(effects
				(font
					(size 1 1)
					(thickness 0.15)
				)
				(justify mirror)
			)
		)
		(property "Val" "80R6"
			(at 0 0 0)
			(layer "B.Fab")
			(hide yes)
			(effects
				(font
					(size 1 1)
					(thickness 0.15)
				)
				(justify mirror)
			)
		)
		(sheetname "FPGA Bank 33 & 34")
		(sheetfile "fpga-bank-33-34.kicad_sch")
		(attr smd)
		(fp_rect
			(start -0.95 0.45)
			(end 0.95 -0.45)
			(stroke
				(width 0.05)
				(type default)
			)
			(fill no)
			(layer "B.CrtYd")
		)
		(fp_line
			(start -0.5 -0.249)
			(end -0.5 0.25)
			(stroke
				(width 0.15)
				(type solid)
			)
			(layer "B.Fab")
		)
		(fp_line
			(start -0.5 0.25)
			(end 0.499 0.25)
			(stroke
				(width 0.15)
				(type solid)
			)
			(layer "B.Fab")
		)
		(fp_line
			(start 0.499 -0.249)
			(end -0.5 -0.249)
			(stroke
				(width 0.15)
				(type solid)
			)
			(layer "B.Fab")
		)
		(fp_line
			(start 0.499 0.25)
			(end 0.499 -0.249)
			(stroke
				(width 0.15)
				(type solid)
			)
			(layer "B.Fab")
		)
		(pad "1" smd roundrect
			(at -0.5 0 270)
			(size 0.6 0.6)
			(layers "B.Cu" "B.Mask" "B.Paste")
			(roundrect_rratio 0.25)
			(net 568 "/FPGA Bank 33 & 34/DDR_VRP")
			(pintype "passive")
		)
		(pad "2" smd roundrect
			(at 0.499 0)
			(size 0.6 0.6)
			(layers "B.Cu" "B.Mask" "B.Paste")
			(roundrect_rratio 0.25)
			(net 25 "+1V35")
			(pintype "passive")
		)
	)
	(footprint "antmicro-footprints:C_0402_1005Metric"
		(layer "B.Cu")
		(at 263.501 181.75 180)
		(descr "Capacitor SMD 0402")
		(tags "capacitor SMD 0402")
		(property "Reference" "C190"
			(at -1.349 -1.25 0)
			(layer "B.SilkS")
			(effects
				(font
					(size 0.7 0.7)
					(thickness 0.15)
				)
				(justify left bottom mirror)
			)
		)
		(property "Value" "C_100n_0402"
			(at 0 -1.4 0)
			(layer "B.Fab")
			(effects
				(font
					(size 0.7 0.7)
					(thickness 0.15)
				)
				(justify left bottom mirror)
			)
		)
		(property "Description" "SMD Multilayer Ceramic Capacitor, 0.1 µF, 50 V, 0402 [1005 Metric], ± 10%, X5R, GRM Series"
			(at 0 0 180)
			(layer "F.Fab")
			(hide yes)
			(effects
				(font
					(size 1.27 1.27)
					(thickness 0.15)
				)
			)
		)
		(property "Author" "Antmicro"
			(at 527.002 363.5 0)
			(layer "B.Fab")
			(hide yes)
			(effects
				(font
					(size 1 1)
					(thickness 0.15)
				)
				(justify mirror)
			)
		)
		(property "Dielectric" "X5R"
			(at 527.002 363.5 0)
			(layer "B.Fab")
			(hide yes)
			(effects
				(font
					(size 1 1)
					(thickness 0.15)
				)
				(justify mirror)
			)
		)
		(property "License" "Apache-2.0"
			(at 527.002 363.5 0)
			(layer "B.Fab")
			(hide yes)
			(effects
				(font
					(size 1 1)
					(thickness 0.15)
				)
				(justify mirror)
			)
		)
		(property "MPN" "GRM155R61H104KE14D"
			(at 527.002 363.5 0)
			(layer "B.Fab")
			(hide yes)
			(effects
				(font
					(size 1 1)
					(thickness 0.15)
				)
				(justify mirror)
			)
		)
		(property "Manufacturer" "Murata"
			(at 527.002 363.5 0)
			(layer "B.Fab")
			(hide yes)
			(effects
				(font
					(size 1 1)
					(thickness 0.15)
				)
				(justify mirror)
			)
		)
		(property "Val" "100n"
			(at 527.002 363.5 0)
			(layer "B.Fab")
			(hide yes)
			(effects
				(font
					(size 1 1)
					(thickness 0.15)
				)
				(justify mirror)
			)
		)
		(property "Voltage" "50V"
			(at 527.002 363.5 0)
			(layer "B.Fab")
			(hide yes)
			(effects
				(font
					(size 1 1)
					(thickness 0.15)
				)
				(justify mirror)
			)
		)
		(sheetname "Power supply")
		(sheetfile "power-supply.kicad_sch")
		(attr smd)
		(fp_rect
			(start -0.925 0.47)
			(end 0.925 -0.47)
			(stroke
				(width 0.05)
				(type default)
			)
			(fill no)
			(layer "B.CrtYd")
		)
		(fp_line
			(start 0.504 0.25)
			(end 0.504 -0.248)
			(stroke
				(width 0.15)
				(type solid)
			)
			(layer "B.Fab")
		)
		(fp_line
			(start 0.504 -0.248)
			(end -0.494 -0.248)
			(stroke
				(width 0.15)
				(type solid)
			)
			(layer "B.Fab")
		)
		(fp_line
			(start -0.494 0.25)
			(end 0.504 0.25)
			(stroke
				(width 0.15)
				(type solid)
			)
			(layer "B.Fab")
		)
		(fp_line
			(start -0.494 -0.248)
			(end -0.494 0.25)
			(stroke
				(width 0.15)
				(type solid)
			)
			(layer "B.Fab")
		)
		(pad "1" smd roundrect
			(at -0.48 0 180)
			(size 0.59 0.64)
			(layers "B.Cu" "B.Mask" "B.Paste")
			(roundrect_rratio 0.25)
			(net 1 "GND")
			(pintype "passive")
		)
		(pad "2" smd roundrect
			(at 0.48 0 180)
			(size 0.59 0.64)
			(layers "B.Cu" "B.Mask" "B.Paste")
			(roundrect_rratio 0.25)
			(net 4 "/Power supply/DC_IN")
			(pintype "passive")
		)
	)
	(footprint "antmicro-footprints:SOT-886"
		(layer "B.Cu")
		(at 258.751 123.15 180)
		(property "Reference" "U48"
			(at -1.099 0.8 0)
			(layer "B.SilkS")
			(effects
				(font
					(size 0.7 0.7)
					(thickness 0.15)
				)
				(justify left bottom mirror)
			)
		)
		(property "Value" "74LVC1T45GM"
			(at -2.492 -1.647 0)
			(layer "B.Fab")
			(effects
				(font
					(size 0.7 0.7)
					(thickness 0.15)
				)
				(justify left bottom mirror)
			)
		)
		(property "Description" "Transceiver, Translating, 74LVC1T45, 74LVC Family, 1.2V to 5.5V Supply, XSON-6"
			(at 0 0 180)
			(layer "F.Fab")
			(hide yes)
			(effects
				(font
					(size 1.27 1.27)
					(thickness 0.15)
				)
			)
		)
		(property "Author" "Antmicro"
			(at 517.502 246.3 0)
			(layer "B.Fab")
			(hide yes)
			(effects
				(font
					(size 1 1)
					(thickness 0.15)
				)
				(justify mirror)
			)
		)
		(property "License" "Apache-2.0"
			(at 517.502 246.3 0)
			(layer "B.Fab")
			(hide yes)
			(effects
				(font
					(size 1 1)
					(thickness 0.15)
				)
				(justify mirror)
			)
		)
		(property "MPN" "74LVC1T45GM-Q100X"
			(at 517.502 246.3 0)
			(layer "B.Fab")
			(hide yes)
			(effects
				(font
					(size 1 1)
					(thickness 0.15)
				)
				(justify mirror)
			)
		)
		(property "Manufacturer" "Nexperia"
			(at 517.502 246.3 0)
			(layer "B.Fab")
			(hide yes)
			(effects
				(font
					(size 1 1)
					(thickness 0.15)
				)
				(justify mirror)
			)
		)
		(sheetname "USB PHY")
		(sheetfile "usb-phy.kicad_sch")
		(attr smd)
		(fp_line
			(start 0.858 0.491)
			(end 0.858 -0.509)
			(stroke
				(width 0.15)
				(type solid)
			)
			(layer "B.SilkS")
		)
		(fp_line
			(start -0.843 0.491)
			(end -0.843 -0.183)
			(stroke
				(width 0.15)
				(type solid)
			)
			(layer "B.SilkS")
		)
		(fp_circle
			(center -0.493 -0.847)
			(end -0.443 -0.847)
			(stroke
				(width 0.15)
				(type solid)
			)
			(fill yes)
			(layer "B.SilkS")
		)
		(fp_rect
			(start -1.23 1)
			(end 1.22 -0.99)
			(stroke
				(width 0.05)
				(type solid)
			)
			(fill no)
			(layer "B.CrtYd")
		)
		(fp_line
			(start 0.858 0.616)
			(end 0.858 -0.634)
			(stroke
				(width 0.15)
				(type solid)
			)
			(layer "B.Fab")
		)
		(fp_line
			(start 0.858 -0.634)
			(end -0.843 -0.634)
			(stroke
				(width 0.15)
				(type solid)
			)
			(layer "B.Fab")
		)
		(fp_line
			(start -0.843 0.616)
			(end 0.858 0.616)
			(stroke
				(width 0.15)
				(type solid)
			)
			(layer "B.Fab")
		)
		(fp_line
			(start -0.843 0.616)
			(end -0.843 -0.634)
			(stroke
				(width 0.15)
				(type solid)
			)
			(layer "B.Fab")
		)
		(fp_line
			(start -0.843 -0.434)
			(end -0.644 -0.634)
			(stroke
				(width 0.15)
				(type solid)
			)
			(layer "B.Fab")
		)
		(pad "1" smd rect
			(at -0.493 -0.347 180)
			(size 0.27 0.325)
			(layers "B.Cu" "B.Mask" "B.Paste")
			(net 707 "/USB PHY/FTDI_3V3")
			(pinfunction "VCCA")
			(pintype "power_in")
			(solder_mask_margin 0.05)
		)
		(pad "2" smd rect
			(at 0.005 -0.347 180)
			(size 0.27 0.325)
			(layers "B.Cu" "B.Mask" "B.Paste")
			(net 1 "GND")
			(pinfunction "GND")
			(pintype "power_in")
			(solder_mask_margin 0.05)
		)
		(pad "3" smd rect
			(at 0.505 -0.347 180)
			(size 0.27 0.325)
			(layers "B.Cu" "B.Mask" "B.Paste")
			(net 1020 "/USB PHY/FTDI_JTAG_RST")
			(pinfunction "A")
			(pintype "bidirectional")
			(solder_mask_margin 0.05)
		)
		(pad "4" smd rect
			(at 0.505 0.33)
			(size 0.27 0.325)
			(layers "B.Cu" "B.Mask" "B.Paste")
			(net 431 "/FPGA Config/JTAG.RST")
			(pinfunction "B")
			(pintype "bidirectional")
			(solder_mask_margin 0.05)
		)
		(pad "5" smd rect
			(at 0.005 0.33)
			(size 0.27 0.325)
			(layers "B.Cu" "B.Mask" "B.Paste")
			(net 707 "/USB PHY/FTDI_3V3")
			(pinfunction "DIR")
			(pintype "input")
			(solder_mask_margin 0.05)
		)
		(pad "6" smd rect
			(at -0.493 0.33)
			(size 0.27 0.325)
			(layers "B.Cu" "B.Mask" "B.Paste")
			(net 24 "+3V3")
			(pinfunction "VCCB")
			(pintype "power_in")
			(solder_mask_margin 0.05)
		)
	)
)
